(kicad_pcb
	(version 20260206)
	(generator "pcbnew")
	(generator_version "10.0")
	(general
		(thickness 1.6)
		(legacy_teardrops no)
	)
	(paper "A4")
	(title_block
		(title "Wiwynn_Tioga_Pass_MB.brd")
		(comment 1 "Tioga Pass / footprint 2096 of 4770 (J4A2), pads 244-291 of 291")
	)
	(layers
		(0 "F.Cu" signal "TOP")
		(4 "In1.Cu" signal "L2GND")
		(6 "In2.Cu" signal "L3")
		(8 "In3.Cu" signal "L4GND")
		(10 "In4.Cu" signal "L5")
		(12 "In5.Cu" signal "L6GND")
		(14 "In6.Cu" signal "L7VCC")
		(16 "In7.Cu" signal "L8VCC")
		(18 "In8.Cu" signal "L9GND")
		(20 "In9.Cu" signal "L10")
		(22 "In10.Cu" signal "L11GND")
		(24 "In11.Cu" signal "L12")
		(26 "In12.Cu" signal "L13GND")
		(2 "B.Cu" signal "BOTTOM")
		(9 "F.Adhes" user "F.Adhesive")
		(11 "B.Adhes" user "B.Adhesive")
		(13 "F.Paste" user "Package Geometry/Pastemask Top")
		(15 "B.Paste" user "Package Geometry/Pastemask Bottom")
		(5 "F.SilkS" user "Ref Des/Silkscreen Top")
		(7 "B.SilkS" user "Ref Des/Silkscreen Bottom")
		(1 "F.Mask" user "Board Geometry/Soldermask Top")
		(3 "B.Mask" user "Board Geometry/Soldermask Bottom")
		(17 "Dwgs.User" user "User.Drawings")
		(19 "Cmts.User" user "User.Comments")
		(21 "Eco1.User" user "User.Eco1")
		(23 "Eco2.User" user "User.Eco2")
		(25 "Edge.Cuts" user "Board Geometry/Outline")
		(27 "Margin" user)
		(31 "F.CrtYd" user "Package Geometry/Place Bound Top")
		(29 "B.CrtYd" user "Package Geometry/Place Bound Bottom")
		(35 "F.Fab" user "Ref Des/Assembly Top")
		(33 "B.Fab" user "Ref Des/Assembly Bottom")
	)
	(footprint ""
		(layer "F.Cu")
		(at 194.700398 -142.6718 90)
		(property "Reference" "J4A2"
			(at -2.369312 42.66311 0)
			(unlocked yes)
			(layer "F.SilkS")
			(effects
				(font
					(size 0.7874 0.5842)
					(thickness 0.1524)
				)
				(justify left)
			)
		)
		(property "Value" ""
			(at 0 0 90)
			(layer "F.Fab")
			(effects
				(font
					(size 1.27 1.27)
				)
			)
		)
		(duplicate_pad_numbers_are_jumpers no)
		(pad "241" smd rect
			(at 4.59994 86.700106 90)
			(size 1.8034 0.508)
			(layers "F.Cu" "F.Mask" "F.Paste")
			(net "GND")
		)
		(pad "242" smd rect
			(at 4.59994 87.54999 90)
			(size 1.8034 0.508)
			(layers "F.Cu" "F.Mask" "F.Paste")
			(net "M_E_DQ<32>")
		)
		(pad "243" smd rect
			(at 4.59994 88.399874 90)
			(size 1.8034 0.508)
			(layers "F.Cu" "F.Mask" "F.Paste")
			(net "GND")
		)
		(pad "244" smd rect
			(at 4.59994 89.250012 90)
			(size 1.8034 0.508)
			(layers "F.Cu" "F.Mask" "F.Paste")
			(net "M_E_DQS_DN<4>")
		)
		(pad "245" smd rect
			(at 4.59994 90.099896 90)
			(size 1.8034 0.508)
			(layers "F.Cu" "F.Mask" "F.Paste")
			(net "M_E_DQS_DP<4>")
		)
		(pad "246" smd rect
			(at 4.59994 90.950034 90)
			(size 1.8034 0.508)
			(layers "F.Cu" "F.Mask" "F.Paste")
			(net "GND")
		)
		(pad "247" smd rect
			(at 4.59994 91.799918 90)
			(size 1.8034 0.508)
			(layers "F.Cu" "F.Mask" "F.Paste")
			(net "M_E_DQ<38>")
		)
		(pad "248" smd rect
			(at 4.59994 92.650056 90)
			(size 1.8034 0.508)
			(layers "F.Cu" "F.Mask" "F.Paste")
			(net "GND")
		)
		(pad "249" smd rect
			(at 4.59994 93.49994 90)
			(size 1.8034 0.508)
			(layers "F.Cu" "F.Mask" "F.Paste")
			(net "M_E_DQ<34>")
		)
		(pad "250" smd rect
			(at 4.59994 94.350078 90)
			(size 1.8034 0.508)
			(layers "F.Cu" "F.Mask" "F.Paste")
			(net "GND")
		)
		(pad "251" smd rect
			(at 4.59994 95.199962 90)
			(size 1.8034 0.508)
			(layers "F.Cu" "F.Mask" "F.Paste")
			(net "M_E_DQ<44>")
		)
		(pad "252" smd rect
			(at 4.59994 96.0501 90)
			(size 1.8034 0.508)
			(layers "F.Cu" "F.Mask" "F.Paste")
			(net "GND")
		)
		(pad "253" smd rect
			(at 4.59994 96.899984 90)
			(size 1.8034 0.508)
			(layers "F.Cu" "F.Mask" "F.Paste")
			(net "M_E_DQ<40>")
		)
		(pad "254" smd rect
			(at 4.59994 97.750122 90)
			(size 1.8034 0.508)
			(layers "F.Cu" "F.Mask" "F.Paste")
			(net "GND")
		)
		(pad "255" smd rect
			(at 4.59994 98.600006 90)
			(size 1.8034 0.508)
			(layers "F.Cu" "F.Mask" "F.Paste")
			(net "M_E_DQS_DN<5>")
		)
		(pad "256" smd rect
			(at 4.59994 99.44989 90)
			(size 1.8034 0.508)
			(layers "F.Cu" "F.Mask" "F.Paste")
			(net "M_E_DQS_DP<5>")
		)
		(pad "257" smd rect
			(at 4.59994 100.300028 90)
			(size 1.8034 0.508)
			(layers "F.Cu" "F.Mask" "F.Paste")
			(net "GND")
		)
		(pad "258" smd rect
			(at 4.59994 101.149912 90)
			(size 1.8034 0.508)
			(layers "F.Cu" "F.Mask" "F.Paste")
			(net "M_E_DQ<46>")
		)
		(pad "259" smd rect
			(at 4.59994 102.00005 90)
			(size 1.8034 0.508)
			(layers "F.Cu" "F.Mask" "F.Paste")
			(net "GND")
		)
		(pad "260" smd rect
			(at 4.59994 102.849934 90)
			(size 1.8034 0.508)
			(layers "F.Cu" "F.Mask" "F.Paste")
			(net "M_E_DQ<42>")
		)
		(pad "261" smd rect
			(at 4.59994 103.700072 90)
			(size 1.8034 0.508)
			(layers "F.Cu" "F.Mask" "F.Paste")
			(net "GND")
		)
		(pad "262" smd rect
			(at 4.59994 104.549956 90)
			(size 1.8034 0.508)
			(layers "F.Cu" "F.Mask" "F.Paste")
			(net "M_E_DQ<52>")
		)
		(pad "263" smd rect
			(at 4.59994 105.400094 90)
			(size 1.8034 0.508)
			(layers "F.Cu" "F.Mask" "F.Paste")
			(net "GND")
		)
		(pad "264" smd rect
			(at 4.59994 106.249978 90)
			(size 1.8034 0.508)
			(layers "F.Cu" "F.Mask" "F.Paste")
			(net "M_E_DQ<48>")
		)
		(pad "265" smd rect
			(at 4.59994 107.100116 90)
			(size 1.8034 0.508)
			(layers "F.Cu" "F.Mask" "F.Paste")
			(net "GND")
		)
		(pad "266" smd rect
			(at 4.59994 107.95 90)
			(size 1.8034 0.508)
			(layers "F.Cu" "F.Mask" "F.Paste")
			(net "M_E_DQS_DN<6>")
		)
		(pad "267" smd rect
			(at 4.59994 108.799884 90)
			(size 1.8034 0.508)
			(layers "F.Cu" "F.Mask" "F.Paste")
			(net "M_E_DQS_DP<6>")
		)
		(pad "268" smd rect
			(at 4.59994 109.650022 90)
			(size 1.8034 0.508)
			(layers "F.Cu" "F.Mask" "F.Paste")
			(net "GND")
		)
		(pad "269" smd rect
			(at 4.59994 110.499906 90)
			(size 1.8034 0.508)
			(layers "F.Cu" "F.Mask" "F.Paste")
			(net "M_E_DQ<54>")
		)
		(pad "270" smd rect
			(at 4.59994 111.350044 90)
			(size 1.8034 0.508)
			(layers "F.Cu" "F.Mask" "F.Paste")
			(net "GND")
		)
		(pad "271" smd rect
			(at 4.59994 112.199928 90)
			(size 1.8034 0.508)
			(layers "F.Cu" "F.Mask" "F.Paste")
			(net "M_E_DQ<50>")
		)
		(pad "272" smd rect
			(at 4.59994 113.050066 90)
			(size 1.8034 0.508)
			(layers "F.Cu" "F.Mask" "F.Paste")
			(net "GND")
		)
		(pad "273" smd rect
			(at 4.59994 113.89995 90)
			(size 1.8034 0.508)
			(layers "F.Cu" "F.Mask" "F.Paste")
			(net "M_E_DQ<60>")
		)
		(pad "274" smd rect
			(at 4.59994 114.750088 90)
			(size 1.8034 0.508)
			(layers "F.Cu" "F.Mask" "F.Paste")
			(net "GND")
		)
		(pad "275" smd rect
			(at 4.59994 115.599972 90)
			(size 1.8034 0.508)
			(layers "F.Cu" "F.Mask" "F.Paste")
			(net "M_E_DQ<56>")
		)
		(pad "276" smd rect
			(at 4.59994 116.45011 90)
			(size 1.8034 0.508)
			(layers "F.Cu" "F.Mask" "F.Paste")
			(net "GND")
		)
		(pad "277" smd rect
			(at 4.59994 117.299994 90)
			(size 1.8034 0.508)
			(layers "F.Cu" "F.Mask" "F.Paste")
			(net "M_E_DQS_DN<7>")
		)
		(pad "278" smd rect
			(at 4.59994 118.149878 90)
			(size 1.8034 0.508)
			(layers "F.Cu" "F.Mask" "F.Paste")
			(net "M_E_DQS_DP<7>")
		)
		(pad "279" smd rect
			(at 4.59994 119.000016 90)
			(size 1.8034 0.508)
			(layers "F.Cu" "F.Mask" "F.Paste")
			(net "GND")
		)
		(pad "280" smd rect
			(at 4.59994 119.8499 90)
			(size 1.8034 0.508)
			(layers "F.Cu" "F.Mask" "F.Paste")
			(net "M_E_DQ<62>")
		)
		(pad "281" smd rect
			(at 4.59994 120.700038 90)
			(size 1.8034 0.508)
			(layers "F.Cu" "F.Mask" "F.Paste")
			(net "GND")
		)
		(pad "282" smd rect
			(at 4.59994 121.549922 90)
			(size 1.8034 0.508)
			(layers "F.Cu" "F.Mask" "F.Paste")
			(net "M_E_DQ<58>")
		)
		(pad "283" smd rect
			(at 4.59994 122.40006 90)
			(size 1.8034 0.508)
			(layers "F.Cu" "F.Mask" "F.Paste")
			(net "GND")
		)
		(pad "284" smd rect
			(at 4.59994 123.249944 90)
			(size 1.8034 0.508)
			(layers "F.Cu" "F.Mask" "F.Paste")
			(net "PVPP_DEF")
		)
		(pad "285" smd rect
			(at 4.59994 124.100082 90)
			(size 1.8034 0.508)
			(layers "F.Cu" "F.Mask" "F.Paste")
			(net "SMB_DDR_DEF_VPP_SDA")
		)
		(pad "286" smd rect
			(at 4.59994 124.949966 90)
			(size 1.8034 0.508)
			(layers "F.Cu" "F.Mask" "F.Paste")
			(net "PVPP_DEF")
		)
		(pad "287" smd rect
			(at 4.59994 125.800104 90)
			(size 1.8034 0.508)
			(layers "F.Cu" "F.Mask" "F.Paste")
			(net "PVPP_DEF")
		)
		(pad "288" smd rect
			(at 4.59994 126.649988 90)
			(size 1.8034 0.508)
			(layers "F.Cu" "F.Mask" "F.Paste")
			(net "PVPP_DEF")
		)
	)
)
